(kicad_pcb
	(version 20260206)
	(generator "pcbnew")
	(generator_version "10.0")
	(general
		(thickness 1.6)
		(legacy_teardrops no)
	)
	(paper "A4")
	(title_block
		(title "pdpb — Lightning_PDPB_BRD.brd")
		(comment 1 "Lightning (Wiwynn / Facebook NVMe JBOF) / footprints 752-758 of 1140")
	)
	(layers
		(0 "F.Cu" signal "TOP")
		(4 "In1.Cu" signal "L2GND")
		(6 "In2.Cu" signal "L3")
		(8 "In3.Cu" signal "L4VCC")
		(10 "In4.Cu" signal "L5VCC")
		(12 "In5.Cu" signal "L6")
		(14 "In6.Cu" signal "L7GND")
		(2 "B.Cu" signal "BOTTOM")
		(9 "F.Adhes" user "F.Adhesive")
		(11 "B.Adhes" user "B.Adhesive")
		(13 "F.Paste" user "Package Geometry/Pastemask Top")
		(15 "B.Paste" user "Package Geometry/Pastemask Bottom")
		(5 "F.SilkS" user "Ref Des/Silkscreen Top")
		(7 "B.SilkS" user "Ref Des/Silkscreen Bottom")
		(1 "F.Mask" user "Board Geometry/Soldermask Top")
		(3 "B.Mask" user "Board Geometry/Soldermask Bottom")
		(17 "Dwgs.User" user "User.Drawings")
		(19 "Cmts.User" user "User.Comments")
		(21 "Eco1.User" user "User.Eco1")
		(23 "Eco2.User" user "User.Eco2")
		(25 "Edge.Cuts" user "Board Geometry/Outline")
		(27 "Margin" user)
		(31 "F.CrtYd" user "Package Geometry/Place Bound Top")
		(29 "B.CrtYd" user "Package Geometry/Place Bound Bottom")
		(35 "F.Fab" user "Ref Des/Assembly Top")
		(33 "B.Fab" user "Ref Des/Assembly Bottom")
	)
	(footprint ""
		(layer "F.Cu")
		(at 35.14725 -350.01454 -90)
		(property "Reference" "SR1133"
			(at 0 0 270)
			(layer "F.SilkS")
			(hide yes)
			(effects
				(font
					(size 1.27 1.27)
				)
			)
		)
		(property "Value" "4K7R2F-GP"
			(at 0.064008 -3.993896 270)
			(unlocked yes)
			(layer "F.Fab")
			(hide yes)
			(effects
				(font
					(size 1.016 1.016)
					(thickness 0.1524)
				)
			)
		)
		(property "Device Type" "R402H16"
			(at 0.064008 -5.517896 270)
			(unlocked yes)
			(layer "F.Fab")
			(hide yes)
			(effects
				(font
					(size 1.016 1.016)
					(thickness 0.1524)
				)
			)
		)
		(duplicate_pad_numbers_are_jumpers no)
		(fp_line
			(start -0.508 -0.9398)
			(end -0.508 0.9398)
			(stroke
				(width 0.1524)
				(type default)
			)
			(layer "F.SilkS")
		)
		(fp_line
			(start 0.508 -0.9398)
			(end -0.508 -0.9398)
			(stroke
				(width 0.1524)
				(type default)
			)
			(layer "F.SilkS")
		)
		(fp_rect
			(start -0.508 0.9398)
			(end 0.508 -0.9398)
			(stroke
				(width 0)
				(type default)
			)
			(fill no)
			(layer "F.CrtYd")
		)
		(fp_rect
			(start -0.508 0.9398)
			(end 0.508 -0.9398)
			(stroke
				(width 0)
				(type default)
			)
			(fill no)
			(layer "F.Fab")
		)
		(pad "1" smd custom
			(at 0 -0.4445 270)
			(size 0.1397 0.1397)
			(layers "F.Cu" "F.Mask" "F.Paste")
			(net "P3V3")
			(options
				(clearance outline)
				(anchor circle)
			)
			(primitives
				(gr_poly
					(pts
						(arc
							(start -0.1778 -0.2794)
							(mid -0.249642 -0.249642)
							(end -0.2794 -0.1778)
						)
						(arc
							(start -0.2794 0.1778)
							(mid -0.249642 0.249642)
							(end -0.1778 0.2794)
						)
						(arc
							(start 0.1778 0.2794)
							(mid 0.249642 0.249642)
							(end 0.2794 0.1778)
						)
						(arc
							(start 0.2794 -0.1778)
							(mid 0.249642 -0.249642)
							(end 0.1778 -0.2794)
						)
					)
					(width 0)
					(fill yes)
				)
			)
		)
		(pad "2" smd custom
			(at 0 0.4445 270)
			(size 0.1397 0.1397)
			(layers "F.Cu" "F.Mask" "F.Paste")
			(net "SSD6_CLK0_OE_MOS_N")
			(options
				(clearance outline)
				(anchor circle)
			)
			(primitives
				(gr_poly
					(pts
						(arc
							(start -0.1778 -0.2794)
							(mid -0.249642 -0.249642)
							(end -0.2794 -0.1778)
						)
						(arc
							(start -0.2794 0.1778)
							(mid -0.249642 0.249642)
							(end -0.1778 0.2794)
						)
						(arc
							(start 0.1778 0.2794)
							(mid 0.249642 0.249642)
							(end 0.2794 0.1778)
						)
						(arc
							(start 0.2794 -0.1778)
							(mid 0.249642 -0.249642)
							(end 0.1778 -0.2794)
						)
					)
					(width 0)
					(fill yes)
				)
			)
		)
	)
	(footprint ""
		(layer "F.Cu")
		(at 40.8686 -416.4584 180)
		(property "Reference" "D28"
			(at 0 0 180)
			(layer "F.SilkS")
			(hide yes)
			(effects
				(font
					(size 1.27 1.27)
				)
			)
		)
		(property "Value" "RB551V30-1-GP"
			(at 0 -6.7818 180)
			(unlocked yes)
			(layer "F.Fab")
			(hide yes)
			(effects
				(font
					(size 1.016 1.016)
					(thickness 0.1524)
				)
			)
		)
		(property "Device Type" "SOD323AKH44"
			(at 0 -8.6868 180)
			(unlocked yes)
			(layer "F.Fab")
			(hide yes)
			(effects
				(font
					(size 1.016 1.016)
					(thickness 0.1524)
				)
			)
		)
		(duplicate_pad_numbers_are_jumpers no)
		(fp_line
			(start 0.889 2.159)
			(end -0.889 2.159)
			(stroke
				(width 0.1524)
				(type default)
			)
			(layer "F.SilkS")
		)
		(fp_line
			(start 0.889 -1.9304)
			(end 0.889 2.159)
			(stroke
				(width 0.1524)
				(type default)
			)
			(layer "F.SilkS")
		)
		(fp_line
			(start 0.762 2.0574)
			(end -0.762 2.0574)
			(stroke
				(width 0.508)
				(type default)
			)
			(layer "F.SilkS")
		)
		(fp_line
			(start -0.889 2.159)
			(end -0.889 -1.9304)
			(stroke
				(width 0.1524)
				(type default)
			)
			(layer "F.SilkS")
		)
		(fp_line
			(start -0.889 -1.9304)
			(end 0.889 -1.9304)
			(stroke
				(width 0.1524)
				(type default)
			)
			(layer "F.SilkS")
		)
		(fp_rect
			(start -1.016 2.3114)
			(end 1.016 -2.0066)
			(stroke
				(width 0)
				(type default)
			)
			(fill no)
			(layer "F.CrtYd")
		)
		(fp_poly
			(pts
				(xy -1.016 -2.0066) (xy 1.016 -2.0066) (xy 1.016 2.3114) (xy -1.016 2.3114)
			)
			(stroke
				(width 0)
				(type default)
			)
			(fill no)
			(layer "F.Fab")
		)
		(pad "A" smd rect
			(at 0 -1.143 180)
			(size 0.5588 1.016)
			(layers "F.Cu" "F.Mask" "F.Paste")
			(net "SW_SSD10_R")
		)
		(pad "K" smd rect
			(at 0 1.143 180)
			(size 0.5588 1.016)
			(layers "F.Cu" "F.Mask" "F.Paste")
			(net "SW_SSD10_N")
		)
	)
	(footprint ""
		(layer "F.Cu")
		(at 87.122 -309.88)
		(property "Reference" "C8909"
			(at 0 0 0)
			(layer "F.SilkS")
			(hide yes)
			(effects
				(font
					(size 1.27 1.27)
				)
			)
		)
		(property "Value" "SC1U10V2KX-7-GP"
			(at 1.1811 -2.7051 0)
			(unlocked yes)
			(layer "F.Fab")
			(hide yes)
			(effects
				(font
					(size 1.016 1.016)
					(thickness 0.1524)
				)
			)
		)
		(property "Device Type" "C402H22"
			(at 1.1811 -4.2291 0)
			(unlocked yes)
			(layer "F.Fab")
			(hide yes)
			(effects
				(font
					(size 1.016 1.016)
					(thickness 0.1524)
				)
			)
		)
		(duplicate_pad_numbers_are_jumpers no)
		(fp_rect
			(start -0.4318 0.9525)
			(end 0.4318 -0.9525)
			(stroke
				(width 0)
				(type default)
			)
			(fill no)
			(layer "F.CrtYd")
		)
		(fp_rect
			(start -0.4318 0.9525)
			(end 0.4318 -0.9525)
			(stroke
				(width 0)
				(type default)
			)
			(fill no)
			(layer "F.Fab")
		)
		(pad "1" smd custom
			(at 0 -0.4445)
			(size 0.1524 0.1524)
			(layers "F.Cu" "F.Mask" "F.Paste")
			(net "VDDA_2")
			(options
				(clearance outline)
				(anchor circle)
			)
			(primitives
				(gr_poly
					(pts
						(arc
							(start 0.3048 -0.2032)
							(mid 0.275042 -0.275042)
							(end 0.2032 -0.3048)
						)
						(arc
							(start -0.2032 -0.3048)
							(mid -0.275042 -0.275042)
							(end -0.3048 -0.2032)
						)
						(arc
							(start -0.3048 0.2032)
							(mid -0.275042 0.275042)
							(end -0.2032 0.3048)
						)
						(arc
							(start 0.2032 0.3048)
							(mid 0.275042 0.275042)
							(end 0.3048 0.2032)
						)
					)
					(width 0)
					(fill yes)
				)
			)
		)
		(pad "2" smd custom
			(at 0 0.4445)
			(size 0.1524 0.1524)
			(layers "F.Cu" "F.Mask" "F.Paste")
			(net "GND")
			(options
				(clearance outline)
				(anchor circle)
			)
			(primitives
				(gr_poly
					(pts
						(arc
							(start 0.3048 -0.2032)
							(mid 0.275042 -0.275042)
							(end 0.2032 -0.3048)
						)
						(arc
							(start -0.2032 -0.3048)
							(mid -0.275042 -0.275042)
							(end -0.3048 -0.2032)
						)
						(arc
							(start -0.3048 0.2032)
							(mid -0.275042 0.275042)
							(end -0.2032 0.3048)
						)
						(arc
							(start 0.2032 0.3048)
							(mid 0.275042 0.275042)
							(end 0.3048 0.2032)
						)
					)
					(width 0)
					(fill yes)
				)
			)
		)
	)
	(footprint ""
		(layer "F.Cu")
		(at 85.471 -99.822 -90)
		(property "Reference" "PR9042"
			(at 0 0 270)
			(layer "F.SilkS")
			(hide yes)
			(effects
				(font
					(size 1.27 1.27)
				)
			)
		)
		(property "Value" "4K7R2F-GP"
			(at 0.064008 -3.993896 270)
			(unlocked yes)
			(layer "F.Fab")
			(hide yes)
			(effects
				(font
					(size 1.016 1.016)
					(thickness 0.1524)
				)
			)
		)
		(property "Device Type" "R402H16"
			(at 0.064008 -5.517896 270)
			(unlocked yes)
			(layer "F.Fab")
			(hide yes)
			(effects
				(font
					(size 1.016 1.016)
					(thickness 0.1524)
				)
			)
		)
		(duplicate_pad_numbers_are_jumpers no)
		(fp_line
			(start -0.508 -0.9398)
			(end -0.508 0.9398)
			(stroke
				(width 0.1524)
				(type default)
			)
			(layer "F.SilkS")
		)
		(fp_line
			(start 0.508 -0.9398)
			(end -0.508 -0.9398)
			(stroke
				(width 0.1524)
				(type default)
			)
			(layer "F.SilkS")
		)
		(fp_rect
			(start -0.508 0.9398)
			(end 0.508 -0.9398)
			(stroke
				(width 0)
				(type default)
			)
			(fill no)
			(layer "F.CrtYd")
		)
		(fp_rect
			(start -0.508 0.9398)
			(end 0.508 -0.9398)
			(stroke
				(width 0)
				(type default)
			)
			(fill no)
			(layer "F.Fab")
		)
		(pad "1" smd custom
			(at 0 -0.4445 270)
			(size 0.1397 0.1397)
			(layers "F.Cu" "F.Mask" "F.Paste")
			(net "CLK_BUF_EU4_SMB_A0_TRI")
			(options
				(clearance outline)
				(anchor circle)
			)
			(primitives
				(gr_poly
					(pts
						(arc
							(start -0.1778 -0.2794)
							(mid -0.249642 -0.249642)
							(end -0.2794 -0.1778)
						)
						(arc
							(start -0.2794 0.1778)
							(mid -0.249642 0.249642)
							(end -0.1778 0.2794)
						)
						(arc
							(start 0.1778 0.2794)
							(mid 0.249642 0.249642)
							(end 0.2794 0.1778)
						)
						(arc
							(start 0.2794 -0.1778)
							(mid 0.249642 -0.249642)
							(end 0.1778 -0.2794)
						)
					)
					(width 0)
					(fill yes)
				)
			)
		)
		(pad "2" smd custom
			(at 0 0.4445 270)
			(size 0.1397 0.1397)
			(layers "F.Cu" "F.Mask" "F.Paste")
			(net "GND")
			(options
				(clearance outline)
				(anchor circle)
			)
			(primitives
				(gr_poly
					(pts
						(arc
							(start -0.1778 -0.2794)
							(mid -0.249642 -0.249642)
							(end -0.2794 -0.1778)
						)
						(arc
							(start -0.2794 0.1778)
							(mid -0.249642 0.249642)
							(end -0.1778 0.2794)
						)
						(arc
							(start 0.1778 0.2794)
							(mid 0.249642 0.249642)
							(end 0.2794 0.1778)
						)
						(arc
							(start 0.2794 -0.1778)
							(mid 0.249642 -0.249642)
							(end 0.1778 -0.2794)
						)
					)
					(width 0)
					(fill yes)
				)
			)
		)
	)
	(footprint ""
		(layer "F.Cu")
		(at 216.789 -492.9632 -90)
		(property "Reference" "R384"
			(at 0 0 270)
			(layer "F.SilkS")
			(hide yes)
			(effects
				(font
					(size 1.27 1.27)
				)
			)
		)
		(property "Value" "0R2J-2-GP"
			(at 0.064008 -3.993896 270)
			(unlocked yes)
			(layer "F.Fab")
			(hide yes)
			(effects
				(font
					(size 1.016 1.016)
					(thickness 0.1524)
				)
			)
		)
		(property "Device Type" "R402H16"
			(at 0.064008 -5.517896 270)
			(unlocked yes)
			(layer "F.Fab")
			(hide yes)
			(effects
				(font
					(size 1.016 1.016)
					(thickness 0.1524)
				)
			)
		)
		(duplicate_pad_numbers_are_jumpers no)
		(fp_line
			(start -0.508 -0.9398)
			(end -0.508 0.9398)
			(stroke
				(width 0.1524)
				(type default)
			)
			(layer "F.SilkS")
		)
		(fp_line
			(start 0.508 -0.9398)
			(end -0.508 -0.9398)
			(stroke
				(width 0.1524)
				(type default)
			)
			(layer "F.SilkS")
		)
		(fp_rect
			(start -0.508 0.9398)
			(end 0.508 -0.9398)
			(stroke
				(width 0)
				(type default)
			)
			(fill no)
			(layer "F.CrtYd")
		)
		(fp_rect
			(start -0.508 0.9398)
			(end 0.508 -0.9398)
			(stroke
				(width 0)
				(type default)
			)
			(fill no)
			(layer "F.Fab")
		)
		(pad "1" smd custom
			(at 0 -0.4445 270)
			(size 0.1397 0.1397)
			(layers "F.Cu" "F.Mask" "F.Paste")
			(net "SDA_DR0_R")
			(options
				(clearance outline)
				(anchor circle)
			)
			(primitives
				(gr_poly
					(pts
						(arc
							(start -0.1778 -0.2794)
							(mid -0.249642 -0.249642)
							(end -0.2794 -0.1778)
						)
						(arc
							(start -0.2794 0.1778)
							(mid -0.249642 0.249642)
							(end -0.1778 0.2794)
						)
						(arc
							(start 0.1778 0.2794)
							(mid 0.249642 0.249642)
							(end 0.2794 0.1778)
						)
						(arc
							(start 0.2794 -0.1778)
							(mid 0.249642 -0.249642)
							(end 0.1778 -0.2794)
						)
					)
					(width 0)
					(fill yes)
				)
			)
		)
		(pad "2" smd custom
			(at 0 0.4445 270)
			(size 0.1397 0.1397)
			(layers "F.Cu" "F.Mask" "F.Paste")
			(net "SDA_DR0")
			(options
				(clearance outline)
				(anchor circle)
			)
			(primitives
				(gr_poly
					(pts
						(arc
							(start -0.1778 -0.2794)
							(mid -0.249642 -0.249642)
							(end -0.2794 -0.1778)
						)
						(arc
							(start -0.2794 0.1778)
							(mid -0.249642 0.249642)
							(end -0.1778 0.2794)
						)
						(arc
							(start 0.1778 0.2794)
							(mid 0.249642 0.249642)
							(end 0.2794 0.1778)
						)
						(arc
							(start 0.2794 -0.1778)
							(mid 0.249642 -0.249642)
							(end 0.1778 -0.2794)
						)
					)
					(width 0)
					(fill yes)
				)
			)
		)
	)
	(footprint ""
		(layer "F.Cu")
		(at 40.4876 -107.4674 180)
		(property "Reference" "D31"
			(at 0 0 180)
			(layer "F.SilkS")
			(hide yes)
			(effects
				(font
					(size 1.27 1.27)
				)
			)
		)
		(property "Value" "RB551V30-1-GP"
			(at 0 -6.7818 180)
			(unlocked yes)
			(layer "F.Fab")
			(hide yes)
			(effects
				(font
					(size 1.016 1.016)
					(thickness 0.1524)
				)
			)
		)
		(property "Device Type" "SOD323AKH44"
			(at 0 -8.6868 180)
			(unlocked yes)
			(layer "F.Fab")
			(hide yes)
			(effects
				(font
					(size 1.016 1.016)
					(thickness 0.1524)
				)
			)
		)
		(duplicate_pad_numbers_are_jumpers no)
		(fp_line
			(start 0.889 2.159)
			(end -0.889 2.159)
			(stroke
				(width 0.1524)
				(type default)
			)
			(layer "F.SilkS")
		)
		(fp_line
			(start 0.889 -1.9304)
			(end 0.889 2.159)
			(stroke
				(width 0.1524)
				(type default)
			)
			(layer "F.SilkS")
		)
		(fp_line
			(start 0.762 2.0574)
			(end -0.762 2.0574)
			(stroke
				(width 0.508)
				(type default)
			)
			(layer "F.SilkS")
		)
		(fp_line
			(start -0.889 2.159)
			(end -0.889 -1.9304)
			(stroke
				(width 0.1524)
				(type default)
			)
			(layer "F.SilkS")
		)
		(fp_line
			(start -0.889 -1.9304)
			(end 0.889 -1.9304)
			(stroke
				(width 0.1524)
				(type default)
			)
			(layer "F.SilkS")
		)
		(fp_rect
			(start -1.016 2.3114)
			(end 1.016 -2.0066)
			(stroke
				(width 0)
				(type default)
			)
			(fill no)
			(layer "F.CrtYd")
		)
		(fp_poly
			(pts
				(xy -1.016 -2.0066) (xy 1.016 -2.0066) (xy 1.016 2.3114) (xy -1.016 2.3114)
			)
			(stroke
				(width 0)
				(type default)
			)
			(fill no)
			(layer "F.Fab")
		)
		(pad "A" smd rect
			(at 0 -1.143 180)
			(size 0.5588 1.016)
			(layers "F.Cu" "F.Mask" "F.Paste")
			(net "SW_SSD13_R")
		)
		(pad "K" smd rect
			(at 0 1.143 180)
			(size 0.5588 1.016)
			(layers "F.Cu" "F.Mask" "F.Paste")
			(net "SW_SSD13_N")
		)
	)
	(footprint ""
		(layer "F.Cu")
		(at 48.641 -36.703 180)
		(property "Reference" "Q73"
			(at 0 0 180)
			(layer "F.SilkS")
			(hide yes)
			(effects
				(font
					(size 1.27 1.27)
				)
			)
		)
		(property "Value" "2N7002A-7-GP"
			(at 0.127 -8.9662 180)
			(unlocked yes)
			(layer "F.Fab")
			(hide yes)
			(effects
				(font
					(size 1.016 1.016)
					(thickness 0.1524)
				)
			)
		)
		(property "Device Type" "SOT23DGS2D4H48"
			(at 0.127 -10.4902 180)
			(unlocked yes)
			(layer "F.Fab")
			(hide yes)
			(effects
				(font
					(size 1.016 1.016)
					(thickness 0.1524)
				)
			)
		)
		(duplicate_pad_numbers_are_jumpers no)
		(fp_line
			(start 1.651 1.778)
			(end 1.651 -1.778)
			(stroke
				(width 0.1524)
				(type default)
			)
			(layer "F.SilkS")
		)
		(fp_line
			(start 1.651 -1.778)
			(end -1.651 -1.778)
			(stroke
				(width 0.1524)
				(type default)
			)
			(layer "F.SilkS")
		)
		(fp_line
			(start -1.651 1.778)
			(end 1.651 1.778)
			(stroke
				(width 0.1524)
				(type default)
			)
			(layer "F.SilkS")
		)
		(fp_line
			(start -1.651 -1.778)
			(end -1.651 1.778)
			(stroke
				(width 0.1524)
				(type default)
			)
			(layer "F.SilkS")
		)
		(fp_poly
			(pts
				(xy -1.778 1.8796) (xy -1.778 -1.8796) (xy 1.778 -1.8796) (xy 1.778 1.8796)
			)
			(stroke
				(width 0)
				(type default)
			)
			(fill no)
			(layer "F.CrtYd")
		)
		(fp_poly
			(pts
				(xy -1.778 1.8796) (xy -1.778 -1.8796) (xy 1.778 -1.8796) (xy 1.778 1.8796)
			)
			(stroke
				(width 0)
				(type default)
			)
			(fill no)
			(layer "F.Fab")
		)
		(pad "D" smd custom
			(at 0 -0.9525 180)
			(size 0.1905 0.1905)
			(layers "F.Cu" "F.Mask" "F.Paste")
			(net "SSD_ACT_DR9_MOS_N")
			(options
				(clearance outline)
				(anchor circle)
			)
			(primitives
				(gr_poly
					(pts
						(arc
							(start -0.1778 0.5715)
							(mid -0.321484 0.511984)
							(end -0.381 0.3683)
						)
						(arc
							(start -0.381 -0.3683)
							(mid -0.321484 -0.511984)
							(end -0.1778 -0.5715)
						)
						(arc
							(start 0.1778 -0.5715)
							(mid 0.321484 -0.511984)
							(end 0.381 -0.3683)
						)
						(arc
							(start 0.381 0.3683)
							(mid 0.321484 0.511984)
							(end 0.1778 0.5715)
						)
					)
					(width 0)
					(fill yes)
				)
			)
		)
		(pad "G" smd custom
			(at -0.98425 0.9525 180)
			(size 0.1905 0.1905)
			(layers "F.Cu" "F.Mask" "F.Paste")
			(net "ATTN_LED_DR9_AND_R")
			(options
				(clearance outline)
				(anchor circle)
			)
			(primitives
				(gr_poly
					(pts
						(arc
							(start -0.1778 0.5715)
							(mid -0.321484 0.511984)
							(end -0.381 0.3683)
						)
						(arc
							(start -0.381 -0.3683)
							(mid -0.321484 -0.511984)
							(end -0.1778 -0.5715)
						)
						(arc
							(start 0.1778 -0.5715)
							(mid 0.321484 -0.511984)
							(end 0.381 -0.3683)
						)
						(arc
							(start 0.381 0.3683)
							(mid 0.321484 0.511984)
							(end 0.1778 0.5715)
						)
					)
					(width 0)
					(fill yes)
				)
			)
		)
		(pad "S" smd custom
			(at 0.98425 0.9525 180)
			(size 0.1905 0.1905)
			(layers "F.Cu" "F.Mask" "F.Paste")
			(net "SSD_ACT_DR9_R")
			(options
				(clearance outline)
				(anchor circle)
			)
			(primitives
				(gr_poly
					(pts
						(arc
							(start -0.1778 0.5715)
							(mid -0.321484 0.511984)
							(end -0.381 0.3683)
						)
						(arc
							(start -0.381 -0.3683)
							(mid -0.321484 -0.511984)
							(end -0.1778 -0.5715)
						)
						(arc
							(start 0.1778 -0.5715)
							(mid 0.321484 -0.511984)
							(end 0.381 -0.3683)
						)
						(arc
							(start 0.381 0.3683)
							(mid 0.321484 0.511984)
							(end 0.1778 0.5715)
						)
					)
					(width 0)
					(fill yes)
				)
			)
		)
	)
)
